(kicad_pcb
	(version 20260206)
	(generator "pcbnew")
	(generator_version "10.0")
	(general
		(thickness 1.6)
		(legacy_teardrops no)
	)
	(paper "A4")
	(title_block
		(title "9052_F0T_PDB_Converter_Brick_F_V03_1208_1600_OCP.brd")
		(comment 1 "Grand Teton / footprints 516-522 of 578")
	)
	(layers
		(0 "F.Cu" signal "TOP")
		(4 "In1.Cu" signal "GND")
		(6 "In2.Cu" signal "IN1")
		(8 "In3.Cu" signal "GND1")
		(10 "In4.Cu" signal "VCC")
		(12 "In5.Cu" signal "VCC1")
		(14 "In6.Cu" signal "GND2")
		(16 "In7.Cu" signal "IN2")
		(18 "In8.Cu" signal "GND3")
		(2 "B.Cu" signal "BOTTOM")
		(9 "F.Adhes" user "F.Adhesive")
		(11 "B.Adhes" user "B.Adhesive")
		(13 "F.Paste" user "Package Geometry/Pastemask Top")
		(15 "B.Paste" user "Package Geometry/Pastemask Bottom")
		(5 "F.SilkS" user "Ref Des/Silkscreen Top")
		(7 "B.SilkS" user "Ref Des/Silkscreen Bottom")
		(1 "F.Mask" user "Board Geometry/Soldermask Top")
		(3 "B.Mask" user "Board Geometry/Soldermask Bottom")
		(17 "Dwgs.User" user "User.Drawings")
		(19 "Cmts.User" user "User.Comments")
		(21 "Eco1.User" user "User.Eco1")
		(23 "Eco2.User" user "User.Eco2")
		(25 "Edge.Cuts" user "Board Geometry/Outline")
		(27 "Margin" user)
		(31 "F.CrtYd" user "Package Geometry/Place Bound Top")
		(29 "B.CrtYd" user "Package Geometry/Place Bound Bottom")
		(35 "F.Fab" user "Ref Des/Assembly Top")
		(33 "B.Fab" user "Ref Des/Assembly Bottom")
	)
	(footprint ""
		(layer "B.Cu")
		(at 220.98 -75.057 -90)
		(property "Reference" "R43"
			(at 0 0 90)
			(layer "B.SilkS")
			(hide yes)
			(effects
				(font
					(size 1.27 1.27)
				)
				(justify mirror)
			)
		)
		(property "Value" ""
			(at 0 0 90)
			(layer "B.Fab")
			(effects
				(font
					(size 1.27 1.27)
				)
				(justify mirror)
			)
		)
		(duplicate_pad_numbers_are_jumpers no)
		(fp_line
			(start -0.7874 0.4064)
			(end 0.7874 0.4064)
			(stroke
				(width 0.1524)
				(type default)
			)
			(layer "B.SilkS")
		)
		(fp_line
			(start 0.7874 0.4064)
			(end 0.7874 -0.4064)
			(stroke
				(width 0.1524)
				(type default)
			)
			(layer "B.SilkS")
		)
		(fp_line
			(start -0.7874 -0.4064)
			(end -0.7874 0.4064)
			(stroke
				(width 0.1524)
				(type default)
			)
			(layer "B.SilkS")
		)
		(fp_line
			(start 0.7874 -0.4064)
			(end -0.7874 -0.4064)
			(stroke
				(width 0.1524)
				(type default)
			)
			(layer "B.SilkS")
		)
		(fp_line
			(start -0.67945 0.3048)
			(end -0.120396 0.3048)
			(stroke
				(width 0.1)
				(type default)
			)
			(layer "B.Fab")
		)
		(fp_line
			(start -0.120396 0.3048)
			(end -0.120396 0.2794)
			(stroke
				(width 0.1)
				(type default)
			)
			(layer "B.Fab")
		)
		(fp_line
			(start 0.12065 0.3048)
			(end 0.67945 0.3048)
			(stroke
				(width 0.1)
				(type default)
			)
			(layer "B.Fab")
		)
		(fp_line
			(start 0.67945 0.3048)
			(end 0.67945 -0.305054)
			(stroke
				(width 0.1)
				(type default)
			)
			(layer "B.Fab")
		)
		(fp_line
			(start -0.120396 0.2794)
			(end 0.12065 0.2794)
			(stroke
				(width 0.1)
				(type default)
			)
			(layer "B.Fab")
		)
		(fp_line
			(start 0.12065 0.2794)
			(end 0.12065 0.3048)
			(stroke
				(width 0.1)
				(type default)
			)
			(layer "B.Fab")
		)
		(fp_line
			(start -0.12065 -0.2794)
			(end -0.12065 -0.3048)
			(stroke
				(width 0.1)
				(type default)
			)
			(layer "B.Fab")
		)
		(fp_line
			(start 0.12065 -0.2794)
			(end -0.12065 -0.2794)
			(stroke
				(width 0.1)
				(type default)
			)
			(layer "B.Fab")
		)
		(fp_line
			(start -0.67945 -0.3048)
			(end -0.67945 0.3048)
			(stroke
				(width 0.1)
				(type default)
			)
			(layer "B.Fab")
		)
		(fp_line
			(start -0.12065 -0.3048)
			(end -0.67945 -0.3048)
			(stroke
				(width 0.1)
				(type default)
			)
			(layer "B.Fab")
		)
		(fp_line
			(start 0.12065 -0.305054)
			(end 0.12065 -0.2794)
			(stroke
				(width 0.1)
				(type default)
			)
			(layer "B.Fab")
		)
		(fp_line
			(start 0.67945 -0.305054)
			(end 0.12065 -0.305054)
			(stroke
				(width 0.1)
				(type default)
			)
			(layer "B.Fab")
		)
		(pad "1" smd circle
			(at 0.40005 0 90)
			(size 0 0)
			(layers "B.Cu" "B.Mask" "B.Paste")
			(net "GND")
		)
		(pad "2" smd circle
			(at -0.40005 0 90)
			(size 0 0)
			(layers "B.Cu" "B.Mask" "B.Paste")
			(net "FRU_ADDR2")
		)
	)
	(footprint ""
		(layer "B.Cu")
		(at 191.36868 -161.464498 -90)
		(property "Reference" "J13"
			(at 3.5052 -5.552948 270)
			(unlocked yes)
			(layer "B.SilkS")
			(effects
				(font
					(size 0.7874 0.5842)
					(thickness 0.1524)
				)
				(justify left mirror)
			)
		)
		(property "Value" ""
			(at 0 0 90)
			(layer "B.Fab")
			(effects
				(font
					(size 1.27 1.27)
				)
				(justify mirror)
			)
		)
		(duplicate_pad_numbers_are_jumpers no)
		(fp_line
			(start 0 4.011168)
			(end 3.330702 -4.771136)
			(stroke
				(width 0.1524)
				(type default)
			)
			(layer "B.SilkS")
		)
		(fp_line
			(start -3.330702 -4.771136)
			(end 0 4.011168)
			(stroke
				(width 0.1524)
				(type default)
			)
			(layer "B.SilkS")
		)
		(fp_line
			(start 3.330702 -4.771136)
			(end -3.330702 -4.771136)
			(stroke
				(width 0.1524)
				(type default)
			)
			(layer "B.SilkS")
		)
		(fp_line
			(start 0 4.011168)
			(end 3.330702 -4.771136)
			(stroke
				(width 0.1)
				(type default)
			)
			(layer "B.Fab")
		)
		(fp_line
			(start -3.330702 -4.771136)
			(end 0 4.011168)
			(stroke
				(width 0.1)
				(type default)
			)
			(layer "B.Fab")
		)
		(fp_line
			(start 3.330702 -4.771136)
			(end -3.330702 -4.771136)
			(stroke
				(width 0.1)
				(type default)
			)
			(layer "B.Fab")
		)
		(pad "1" thru_hole circle
			(at 0 0 90)
			(size 2.159 2.159)
			(drill 1.7018)
			(layers "*.Cu" "*.Mask")
			(remove_unused_layers no)
			(net "GND3")
			(clearance 0.0254)
			(thermal_gap 0.0254)
		)
		(pad "2" thru_hole circle
			(at 1.27 -3.348736 90)
			(size 2.159 2.159)
			(drill 1.7018)
			(layers "*.Cu" "*.Mask")
			(remove_unused_layers no)
			(net "TDR_SE_50_OHM_IN2")
			(clearance 0.0254)
			(thermal_gap 0.0254)
		)
		(pad "3" thru_hole circle
			(at -1.27 -3.348736 90)
			(size 2.159 2.159)
			(drill 1.7018)
			(layers "*.Cu" "*.Mask")
			(remove_unused_layers no)
			(net "TDR_SE_50_OHM_IN2")
			(clearance 0.0254)
			(thermal_gap 0.0254)
		)
	)
	(footprint ""
		(layer "B.Cu")
		(at 183.896 -76.708 -90)
		(property "Reference" "PR323"
			(at 0 0 90)
			(layer "B.SilkS")
			(hide yes)
			(effects
				(font
					(size 1.27 1.27)
				)
				(justify mirror)
			)
		)
		(property "Value" ""
			(at 0 0 90)
			(layer "B.Fab")
			(effects
				(font
					(size 1.27 1.27)
				)
				(justify mirror)
			)
		)
		(duplicate_pad_numbers_are_jumpers no)
		(fp_line
			(start -0.7874 0.4064)
			(end 0.7874 0.4064)
			(stroke
				(width 0.1524)
				(type default)
			)
			(layer "B.SilkS")
		)
		(fp_line
			(start 0.7874 0.4064)
			(end 0.7874 -0.4064)
			(stroke
				(width 0.1524)
				(type default)
			)
			(layer "B.SilkS")
		)
		(fp_line
			(start -0.7874 -0.4064)
			(end -0.7874 0.4064)
			(stroke
				(width 0.1524)
				(type default)
			)
			(layer "B.SilkS")
		)
		(fp_line
			(start 0.7874 -0.4064)
			(end -0.7874 -0.4064)
			(stroke
				(width 0.1524)
				(type default)
			)
			(layer "B.SilkS")
		)
		(fp_line
			(start -0.67945 0.3048)
			(end -0.120396 0.3048)
			(stroke
				(width 0.1)
				(type default)
			)
			(layer "B.Fab")
		)
		(fp_line
			(start -0.120396 0.3048)
			(end -0.120396 0.2794)
			(stroke
				(width 0.1)
				(type default)
			)
			(layer "B.Fab")
		)
		(fp_line
			(start 0.12065 0.3048)
			(end 0.67945 0.3048)
			(stroke
				(width 0.1)
				(type default)
			)
			(layer "B.Fab")
		)
		(fp_line
			(start 0.67945 0.3048)
			(end 0.67945 -0.305054)
			(stroke
				(width 0.1)
				(type default)
			)
			(layer "B.Fab")
		)
		(fp_line
			(start -0.120396 0.2794)
			(end 0.12065 0.2794)
			(stroke
				(width 0.1)
				(type default)
			)
			(layer "B.Fab")
		)
		(fp_line
			(start 0.12065 0.2794)
			(end 0.12065 0.3048)
			(stroke
				(width 0.1)
				(type default)
			)
			(layer "B.Fab")
		)
		(fp_line
			(start -0.12065 -0.2794)
			(end -0.12065 -0.3048)
			(stroke
				(width 0.1)
				(type default)
			)
			(layer "B.Fab")
		)
		(fp_line
			(start 0.12065 -0.2794)
			(end -0.12065 -0.2794)
			(stroke
				(width 0.1)
				(type default)
			)
			(layer "B.Fab")
		)
		(fp_line
			(start -0.67945 -0.3048)
			(end -0.67945 0.3048)
			(stroke
				(width 0.1)
				(type default)
			)
			(layer "B.Fab")
		)
		(fp_line
			(start -0.12065 -0.3048)
			(end -0.67945 -0.3048)
			(stroke
				(width 0.1)
				(type default)
			)
			(layer "B.Fab")
		)
		(fp_line
			(start 0.12065 -0.305054)
			(end 0.12065 -0.2794)
			(stroke
				(width 0.1)
				(type default)
			)
			(layer "B.Fab")
		)
		(fp_line
			(start 0.67945 -0.305054)
			(end 0.12065 -0.305054)
			(stroke
				(width 0.1)
				(type default)
			)
			(layer "B.Fab")
		)
		(pad "1" smd circle
			(at 0.40005 0 90)
			(size 0 0)
			(layers "B.Cu" "B.Mask" "B.Paste")
			(net "P12V_MB2_SENSE+")
		)
		(pad "2" smd circle
			(at -0.40005 0 90)
			(size 0 0)
			(layers "B.Cu" "B.Mask" "B.Paste")
			(net "P12V_MB1_SENSE+")
		)
	)
	(footprint ""
		(layer "B.Cu")
		(at 56.850026 -116.078 -90)
		(property "Reference" "R177"
			(at 0 0 90)
			(layer "B.SilkS")
			(hide yes)
			(effects
				(font
					(size 1.27 1.27)
				)
				(justify mirror)
			)
		)
		(property "Value" ""
			(at 0 0 90)
			(layer "B.Fab")
			(effects
				(font
					(size 1.27 1.27)
				)
				(justify mirror)
			)
		)
		(duplicate_pad_numbers_are_jumpers no)
		(fp_line
			(start -0.7874 0.4064)
			(end 0.7874 0.4064)
			(stroke
				(width 0.1524)
				(type default)
			)
			(layer "B.SilkS")
		)
		(fp_line
			(start 0.7874 0.4064)
			(end 0.7874 -0.4064)
			(stroke
				(width 0.1524)
				(type default)
			)
			(layer "B.SilkS")
		)
		(fp_line
			(start -0.7874 -0.4064)
			(end -0.7874 0.4064)
			(stroke
				(width 0.1524)
				(type default)
			)
			(layer "B.SilkS")
		)
		(fp_line
			(start 0.7874 -0.4064)
			(end -0.7874 -0.4064)
			(stroke
				(width 0.1524)
				(type default)
			)
			(layer "B.SilkS")
		)
		(fp_line
			(start -0.67945 0.3048)
			(end -0.120396 0.3048)
			(stroke
				(width 0.1)
				(type default)
			)
			(layer "B.Fab")
		)
		(fp_line
			(start -0.120396 0.3048)
			(end -0.120396 0.2794)
			(stroke
				(width 0.1)
				(type default)
			)
			(layer "B.Fab")
		)
		(fp_line
			(start 0.12065 0.3048)
			(end 0.67945 0.3048)
			(stroke
				(width 0.1)
				(type default)
			)
			(layer "B.Fab")
		)
		(fp_line
			(start 0.67945 0.3048)
			(end 0.67945 -0.305054)
			(stroke
				(width 0.1)
				(type default)
			)
			(layer "B.Fab")
		)
		(fp_line
			(start -0.120396 0.2794)
			(end 0.12065 0.2794)
			(stroke
				(width 0.1)
				(type default)
			)
			(layer "B.Fab")
		)
		(fp_line
			(start 0.12065 0.2794)
			(end 0.12065 0.3048)
			(stroke
				(width 0.1)
				(type default)
			)
			(layer "B.Fab")
		)
		(fp_line
			(start -0.12065 -0.2794)
			(end -0.12065 -0.3048)
			(stroke
				(width 0.1)
				(type default)
			)
			(layer "B.Fab")
		)
		(fp_line
			(start 0.12065 -0.2794)
			(end -0.12065 -0.2794)
			(stroke
				(width 0.1)
				(type default)
			)
			(layer "B.Fab")
		)
		(fp_line
			(start -0.67945 -0.3048)
			(end -0.67945 0.3048)
			(stroke
				(width 0.1)
				(type default)
			)
			(layer "B.Fab")
		)
		(fp_line
			(start -0.12065 -0.3048)
			(end -0.67945 -0.3048)
			(stroke
				(width 0.1)
				(type default)
			)
			(layer "B.Fab")
		)
		(fp_line
			(start 0.12065 -0.305054)
			(end 0.12065 -0.2794)
			(stroke
				(width 0.1)
				(type default)
			)
			(layer "B.Fab")
		)
		(fp_line
			(start 0.67945 -0.305054)
			(end 0.12065 -0.305054)
			(stroke
				(width 0.1)
				(type default)
			)
			(layer "B.Fab")
		)
		(pad "1" smd circle
			(at 0.40005 0 90)
			(size 0 0)
			(layers "B.Cu" "B.Mask" "B.Paste")
			(net "BRICK_P12V_1_EN_N")
		)
		(pad "2" smd circle
			(at -0.40005 0 90)
			(size 0 0)
			(layers "B.Cu" "B.Mask" "B.Paste")
			(net "BRICK_P12V3_ON_OFF_R")
		)
	)
	(footprint ""
		(layer "B.Cu")
		(at 107.319826 -113.792)
		(property "Reference" "U24"
			(at -0.512826 -2.38633 0)
			(unlocked yes)
			(layer "B.SilkS")
			(effects
				(font
					(size 0.7874 0.5842)
					(thickness 0.1524)
				)
				(justify left mirror)
			)
		)
		(property "Value" ""
			(at 0 0 0)
			(layer "B.Fab")
			(effects
				(font
					(size 1.27 1.27)
				)
				(justify mirror)
			)
		)
		(duplicate_pad_numbers_are_jumpers no)
		(fp_line
			(start -1.603248 -1.500124)
			(end -1.603248 1.500124)
			(stroke
				(width 0.1524)
				(type default)
			)
			(layer "B.SilkS")
		)
		(fp_line
			(start -1.603248 1.500124)
			(end 1.603248 1.500124)
			(stroke
				(width 0.1524)
				(type default)
			)
			(layer "B.SilkS")
		)
		(fp_line
			(start 1.603248 -1.500124)
			(end -1.603248 -1.500124)
			(stroke
				(width 0.1524)
				(type default)
			)
			(layer "B.SilkS")
		)
		(fp_line
			(start 1.603248 1.500124)
			(end 1.603248 -1.500124)
			(stroke
				(width 0.1524)
				(type default)
			)
			(layer "B.SilkS")
		)
		(fp_line
			(start -1.249934 -0.219964)
			(end -0.700024 -0.219964)
			(stroke
				(width 0.1)
				(type default)
			)
			(layer "B.Fab")
		)
		(fp_line
			(start -1.249934 0.219964)
			(end -1.249934 -0.219964)
			(stroke
				(width 0.1)
				(type default)
			)
			(layer "B.Fab")
		)
		(fp_line
			(start -0.700024 -1.500124)
			(end 0.700024 -1.500124)
			(stroke
				(width 0.1)
				(type default)
			)
			(layer "B.Fab")
		)
		(fp_line
			(start -0.700024 -0.219964)
			(end -0.700024 -1.500124)
			(stroke
				(width 0.1)
				(type default)
			)
			(layer "B.Fab")
		)
		(fp_line
			(start -0.700024 0.219964)
			(end -1.249934 0.219964)
			(stroke
				(width 0.1)
				(type default)
			)
			(layer "B.Fab")
		)
		(fp_line
			(start -0.700024 1.500124)
			(end -0.700024 0.219964)
			(stroke
				(width 0.1)
				(type default)
			)
			(layer "B.Fab")
		)
		(fp_line
			(start 0.6985 -0.729996)
			(end 0.6985 0.729996)
			(stroke
				(width 0.1)
				(type default)
			)
			(layer "B.Fab")
		)
		(fp_line
			(start 0.6985 0.729996)
			(end 1.249934 0.729996)
			(stroke
				(width 0.1)
				(type default)
			)
			(layer "B.Fab")
		)
		(fp_line
			(start 0.700024 -1.500124)
			(end 0.700024 -1.169924)
			(stroke
				(width 0.1)
				(type default)
			)
			(layer "B.Fab")
		)
		(fp_line
			(start 0.700024 -1.169924)
			(end 1.249934 -1.169924)
			(stroke
				(width 0.1)
				(type default)
			)
			(layer "B.Fab")
		)
		(fp_line
			(start 0.700024 1.169924)
			(end 0.700024 1.500124)
			(stroke
				(width 0.1)
				(type default)
			)
			(layer "B.Fab")
		)
		(fp_line
			(start 0.700024 1.500124)
			(end -0.700024 1.500124)
			(stroke
				(width 0.1)
				(type default)
			)
			(layer "B.Fab")
		)
		(fp_line
			(start 1.249934 -1.169924)
			(end 1.249934 -0.729996)
			(stroke
				(width 0.1)
				(type default)
			)
			(layer "B.Fab")
		)
		(fp_line
			(start 1.249934 -0.729996)
			(end 0.6985 -0.729996)
			(stroke
				(width 0.1)
				(type default)
			)
			(layer "B.Fab")
		)
		(fp_line
			(start 1.249934 0.729996)
			(end 1.249934 1.169924)
			(stroke
				(width 0.1)
				(type default)
			)
			(layer "B.Fab")
		)
		(fp_line
			(start 1.249934 1.169924)
			(end 0.700024 1.169924)
			(stroke
				(width 0.1)
				(type default)
			)
			(layer "B.Fab")
		)
		(fp_rect
			(start 0.700024 1.500124)
			(end -0.700024 -1.500124)
			(stroke
				(width 0)
				(type default)
			)
			(fill no)
			(layer "B.Fab")
		)
		(pad "D" smd rect
			(at -0.999998 0 270)
			(size 0.8128 0.9144)
			(layers "B.Cu" "B.Mask" "B.Paste")
			(net "BRICK_P12V_EN_R_N")
		)
		(pad "G" smd rect
			(at 0.999998 -0.94996 270)
			(size 0.8128 0.9144)
			(layers "B.Cu" "B.Mask" "B.Paste")
			(net "P12V_BRICK0_PWRGD")
		)
		(pad "S" smd rect
			(at 0.999998 0.94996 270)
			(size 0.8128 0.9144)
			(layers "B.Cu" "B.Mask" "B.Paste")
			(net "GND")
		)
	)
	(footprint ""
		(layer "B.Cu")
		(at 53.594 -6.604)
		(property "Reference" ""
			(at 0 0 0)
			(layer "B.SilkS")
			(hide yes)
			(effects
				(font
					(size 1.27 1.27)
				)
				(justify mirror)
			)
		)
		(property "Value" ""
			(at 0 0 0)
			(layer "B.Fab")
			(effects
				(font
					(size 1.27 1.27)
				)
				(justify mirror)
			)
		)
		(duplicate_pad_numbers_are_jumpers no)
		(pad "1" smd circle
			(at 0 0 180)
			(size 0.9906 0.9906)
			(layers "B.Cu" "B.Mask" "B.Paste")
			(net "Net_153")
		)
		(zone
			(layer "B.Cu")
			(hatch none 0.5)
			(connect_pads
				(clearance 0)
			)
			(min_thickness 0.25)
			(keepout
				(tracks not_allowed)
				(vias allowed)
				(pads allowed)
				(copperpour not_allowed)
				(footprints allowed)
			)
			(placement
				(enabled no)
				(sheetname "")
			)
			(fill
				(thermal_gap 0.5)
				(thermal_bridge_width 0.5)
				(island_removal_mode 0)
			)
			(polygon
				(pts
					(arc
						(start 55.2196 -6.604)
						(mid 51.9684 -6.604)
						(end 55.2196 -6.604)
					)
				)
			)
		)
	)
	(footprint ""
		(layer "B.Cu")
		(at 213.614 -69.723 -90)
		(property "Reference" "R92"
			(at 0 0 90)
			(layer "B.SilkS")
			(hide yes)
			(effects
				(font
					(size 1.27 1.27)
				)
				(justify mirror)
			)
		)
		(property "Value" ""
			(at 0 0 90)
			(layer "B.Fab")
			(effects
				(font
					(size 1.27 1.27)
				)
				(justify mirror)
			)
		)
		(duplicate_pad_numbers_are_jumpers no)
		(fp_line
			(start -0.7874 0.4064)
			(end 0.7874 0.4064)
			(stroke
				(width 0.1524)
				(type default)
			)
			(layer "B.SilkS")
		)
		(fp_line
			(start 0.7874 0.4064)
			(end 0.7874 -0.4064)
			(stroke
				(width 0.1524)
				(type default)
			)
			(layer "B.SilkS")
		)
		(fp_line
			(start -0.7874 -0.4064)
			(end -0.7874 0.4064)
			(stroke
				(width 0.1524)
				(type default)
			)
			(layer "B.SilkS")
		)
		(fp_line
			(start 0.7874 -0.4064)
			(end -0.7874 -0.4064)
			(stroke
				(width 0.1524)
				(type default)
			)
			(layer "B.SilkS")
		)
		(fp_line
			(start -0.67945 0.3048)
			(end -0.120396 0.3048)
			(stroke
				(width 0.1)
				(type default)
			)
			(layer "B.Fab")
		)
		(fp_line
			(start -0.120396 0.3048)
			(end -0.120396 0.2794)
			(stroke
				(width 0.1)
				(type default)
			)
			(layer "B.Fab")
		)
		(fp_line
			(start 0.12065 0.3048)
			(end 0.67945 0.3048)
			(stroke
				(width 0.1)
				(type default)
			)
			(layer "B.Fab")
		)
		(fp_line
			(start 0.67945 0.3048)
			(end 0.67945 -0.305054)
			(stroke
				(width 0.1)
				(type default)
			)
			(layer "B.Fab")
		)
		(fp_line
			(start -0.120396 0.2794)
			(end 0.12065 0.2794)
			(stroke
				(width 0.1)
				(type default)
			)
			(layer "B.Fab")
		)
		(fp_line
			(start 0.12065 0.2794)
			(end 0.12065 0.3048)
			(stroke
				(width 0.1)
				(type default)
			)
			(layer "B.Fab")
		)
		(fp_line
			(start -0.12065 -0.2794)
			(end -0.12065 -0.3048)
			(stroke
				(width 0.1)
				(type default)
			)
			(layer "B.Fab")
		)
		(fp_line
			(start 0.12065 -0.2794)
			(end -0.12065 -0.2794)
			(stroke
				(width 0.1)
				(type default)
			)
			(layer "B.Fab")
		)
		(fp_line
			(start -0.67945 -0.3048)
			(end -0.67945 0.3048)
			(stroke
				(width 0.1)
				(type default)
			)
			(layer "B.Fab")
		)
		(fp_line
			(start -0.12065 -0.3048)
			(end -0.67945 -0.3048)
			(stroke
				(width 0.1)
				(type default)
			)
			(layer "B.Fab")
		)
		(fp_line
			(start 0.12065 -0.305054)
			(end 0.12065 -0.2794)
			(stroke
				(width 0.1)
				(type default)
			)
			(layer "B.Fab")
		)
		(fp_line
			(start 0.67945 -0.305054)
			(end 0.12065 -0.305054)
			(stroke
				(width 0.1)
				(type default)
			)
			(layer "B.Fab")
		)
		(pad "1" smd circle
			(at 0.40005 0 90)
			(size 0 0)
			(layers "B.Cu" "B.Mask" "B.Paste")
			(net "P3V3_AUX")
		)
		(pad "2" smd circle
			(at -0.40005 0 90)
			(size 0 0)
			(layers "B.Cu" "B.Mask" "B.Paste")
			(net "SKU_ID_0")
		)
	)
)
